(kicad_pcb
	(version 20241229)
	(generator "pcbnew")
	(generator_version "9.0")
	(general
		(thickness 1.62)
		(legacy_teardrops no)
	)
	(paper "A3")
	(title_block
		(title "COM Express 7 Baseboard")
		(date "2025-02-04")
		(rev "1.1.2")
		(company "Antmicro Ltd")
		(comment 1 "www.antmicro.com")
		(comment 9 "footprints 463-465 of 802")
	)
	(layers
		(0 "F.Cu" signal)
		(4 "In1.Cu" signal)
		(6 "In2.Cu" signal)
		(8 "In3.Cu" signal)
		(10 "In4.Cu" signal)
		(12 "In5.Cu" signal)
		(14 "In6.Cu" signal)
		(2 "B.Cu" signal)
		(9 "F.Adhes" user "F.Adhesive")
		(11 "B.Adhes" user "B.Adhesive")
		(13 "F.Paste" user)
		(15 "B.Paste" user)
		(5 "F.SilkS" user "F.Silkscreen")
		(7 "B.SilkS" user "B.Silkscreen")
		(1 "F.Mask" user)
		(3 "B.Mask" user)
		(17 "Dwgs.User" user "User.Drawings")
		(19 "Cmts.User" user "User.Comments")
		(21 "Eco1.User" user "User.Eco1")
		(23 "Eco2.User" user "User.Eco2")
		(25 "Edge.Cuts" user)
		(27 "Margin" user)
		(31 "F.CrtYd" user "F.Courtyard")
		(29 "B.CrtYd" user "B.Courtyard")
		(35 "F.Fab" user)
		(33 "B.Fab" user)
	)
	(footprint "antmicro-footprints:SOT-23-5"
		(layer "F.Cu")
		(at 296.75 101.161 -90)
		(property "Reference" "U23"
			(at 2.849 -1.1 180)
			(layer "F.SilkS")
			(effects
				(font
					(size 0.7 0.7)
					(thickness 0.15)
				)
				(justify right bottom)
			)
		)
		(property "Value" "TLV73333PDBVT"
			(at 0.002 2.799 90)
			(layer "F.Fab")
			(effects
				(font
					(size 0.7 0.7)
					(thickness 0.15)
				)
				(justify right bottom)
			)
		)
		(property "Datasheet" "https://www.ti.com/lit/ds/symlink/tlv733p.pdf?ts=1702303961350&ref_url=https%253A%252F%252Fwww.ti.com%252Fproduct%252FTLV733P%252Fpart-details%252FTLV73330PDBVR"
			(at 0 0 270)
			(layer "F.Fab")
			(hide yes)
			(effects
				(font
					(size 1.27 1.27)
					(thickness 0.15)
				)
			)
		)
		(property "Author" "Antmicro"
			(at 195.589 397.911 0)
			(layer "F.Fab")
			(hide yes)
			(effects
				(font
					(size 1 1)
					(thickness 0.15)
				)
			)
		)
		(property "License" "Apache-2.0"
			(at 195.589 397.911 0)
			(layer "F.Fab")
			(hide yes)
			(effects
				(font
					(size 1 1)
					(thickness 0.15)
				)
			)
		)
		(property "MPN" "TLV73333PDBVT"
			(at 195.589 397.911 0)
			(layer "F.Fab")
			(hide yes)
			(effects
				(font
					(size 1 1)
					(thickness 0.15)
				)
			)
		)
		(property "Manufacturer" "Texas Instruments"
			(at 195.589 397.911 0)
			(layer "F.Fab")
			(hide yes)
			(effects
				(font
					(size 1 1)
					(thickness 0.15)
				)
			)
		)
		(sheetname "Power")
		(sheetfile "power.kicad_sch")
		(attr smd)
		(fp_line
			(start -0.85 1.6)
			(end -0.85 1.301)
			(stroke
				(width 0.15)
				(type solid)
			)
			(layer "F.SilkS")
		)
		(fp_line
			(start -0.55 1.6)
			(end -0.85 1.6)
			(stroke
				(width 0.15)
				(type solid)
			)
			(layer "F.SilkS")
		)
		(fp_line
			(start 0.8 1.599)
			(end 0.549 1.599)
			(stroke
				(width 0.15)
				(type solid)
			)
			(layer "F.SilkS")
		)
		(fp_line
			(start 0.8 1.3)
			(end 0.8 1.599)
			(stroke
				(width 0.15)
				(type solid)
			)
			(layer "F.SilkS")
		)
		(fp_line
			(start 0.8 0.55)
			(end 0.8 -0.55)
			(stroke
				(width 0.15)
				(type solid)
			)
			(layer "F.SilkS")
		)
		(fp_line
			(start 0.8 -1.3)
			(end 0.8 -1.6)
			(stroke
				(width 0.15)
				(type solid)
			)
			(layer "F.SilkS")
		)
		(fp_line
			(start -0.8 -1.6)
			(end -0.8 -1.3)
			(stroke
				(width 0.15)
				(type solid)
			)
			(layer "F.SilkS")
		)
		(fp_line
			(start -0.8 -1.6)
			(end -0.5 -1.6)
			(stroke
				(width 0.15)
				(type solid)
			)
			(layer "F.SilkS")
		)
		(fp_line
			(start 0.8 -1.6)
			(end 0.5 -1.6)
			(stroke
				(width 0.15)
				(type solid)
			)
			(layer "F.SilkS")
		)
		(fp_circle
			(center -1.25 -1.5)
			(end -1.2 -1.5)
			(stroke
				(width 0.15)
				(type solid)
			)
			(fill yes)
			(layer "F.SilkS")
		)
		(fp_rect
			(start 1.9 -1.76)
			(end -1.9 1.75)
			(stroke
				(width 0.05)
				(type solid)
			)
			(fill no)
			(layer "F.CrtYd")
		)
		(fp_line
			(start -0.398 -1.526)
			(end -0.874 -1.05)
			(stroke
				(width 0.15)
				(type solid)
			)
			(layer "F.Fab")
		)
		(fp_rect
			(start 0.874 1.523)
			(end -0.873 -1.525)
			(stroke
				(width 0.15)
				(type solid)
			)
			(fill no)
			(layer "F.Fab")
		)
		(pad "1" smd rect
			(at -1.351 -0.951 180)
			(size 0.55 1)
			(layers "F.Cu" "F.Mask" "F.Paste")
			(net 77 "+5V_AON")
			(pinfunction "VIN")
			(pintype "power_in")
			(teardrops
				(best_length_ratio 0.2)
				(max_length 1)
				(best_width_ratio 0.9)
				(max_width 2)
				(curved_edges yes)
				(filter_ratio 0.9)
				(enabled yes)
				(allow_two_segments yes)
				(prefer_zone_connections yes)
			)
		)
		(pad "2" smd rect
			(at -1.351 0 180)
			(size 0.55 1)
			(layers "F.Cu" "F.Mask" "F.Paste")
			(net 1 "GND")
			(pinfunction "GND")
			(pintype "power_in")
			(teardrops
				(best_length_ratio 0.2)
				(max_length 1)
				(best_width_ratio 0.9)
				(max_width 2)
				(curved_edges yes)
				(filter_ratio 0.9)
				(enabled yes)
				(allow_two_segments yes)
				(prefer_zone_connections yes)
			)
		)
		(pad "3" smd rect
			(at -1.351 0.949 180)
			(size 0.55 1)
			(layers "F.Cu" "F.Mask" "F.Paste")
			(net 77 "+5V_AON")
			(pinfunction "EN")
			(pintype "input")
			(teardrops
				(best_length_ratio 0.2)
				(max_length 1)
				(best_width_ratio 0.9)
				(max_width 2)
				(curved_edges yes)
				(filter_ratio 0.9)
				(enabled yes)
				(allow_two_segments yes)
				(prefer_zone_connections yes)
			)
		)
		(pad "4" smd rect
			(at 1.35 0.949 180)
			(size 0.55 1)
			(layers "F.Cu" "F.Mask" "F.Paste")
			(net 779 "unconnected-(U23-NC-Pad4)")
			(pinfunction "NC")
			(pintype "no_connect")
			(teardrops
				(best_length_ratio 0.2)
				(max_length 1)
				(best_width_ratio 0.9)
				(max_width 2)
				(curved_edges yes)
				(filter_ratio 0.9)
				(enabled yes)
				(allow_two_segments yes)
				(prefer_zone_connections yes)
			)
		)
		(pad "5" smd rect
			(at 1.35 -0.951 180)
			(size 0.55 1)
			(layers "F.Cu" "F.Mask" "F.Paste")
			(net 79 "Net-(U23-VOUT)")
			(pinfunction "VOUT")
			(pintype "power_out")
			(teardrops
				(best_length_ratio 0.2)
				(max_length 1)
				(best_width_ratio 0.9)
				(max_width 2)
				(curved_edges yes)
				(filter_ratio 0.9)
				(enabled yes)
				(allow_two_segments yes)
				(prefer_zone_connections yes)
			)
		)
	)
	(footprint "antmicro-footprints:Spacer_Drill3.7mm_H5mm_9774050151R"
		(layer "F.Cu")
		(at 237.93 167.8 90)
		(descr "Spacer M=3 h=5mm fi=5.1mm")
		(property "Reference" "H8"
			(at -0.59 4.26 90)
			(layer "F.SilkS")
			(hide yes)
			(effects
				(font
					(size 0.7 0.7)
					(thickness 0.15)
				)
				(justify left bottom)
			)
		)
		(property "Value" "Spacer_Drill3.7mm_H5mm_9774050151R"
			(at 0 4 90)
			(layer "F.Fab")
			(effects
				(font
					(size 0.7 0.7)
					(thickness 0.15)
				)
				(justify left bottom)
			)
		)
		(property "Datasheet" "https://www.we-online.com/catalog/datasheet/9774050151.pdf"
			(at 0 0 90)
			(layer "F.Fab")
			(hide yes)
			(effects
				(font
					(size 1.27 1.27)
					(thickness 0.15)
				)
			)
		)
		(property "Author" "Antmicro"
			(at 405.75 -70.13 0)
			(layer "F.Fab")
			(hide yes)
			(effects
				(font
					(size 1 1)
					(thickness 0.15)
				)
			)
		)
		(property "License" "Apache-2.0"
			(at 405.75 -70.13 0)
			(layer "F.Fab")
			(hide yes)
			(effects
				(font
					(size 1 1)
					(thickness 0.15)
				)
			)
		)
		(property "MPN" "9774050151R"
			(at 405.75 -70.13 0)
			(layer "F.Fab")
			(hide yes)
			(effects
				(font
					(size 1 1)
					(thickness 0.15)
				)
			)
		)
		(property "Manufacturer" "Würth Elektronik"
			(at 405.75 -70.13 0)
			(layer "F.Fab")
			(hide yes)
			(effects
				(font
					(size 1 1)
					(thickness 0.15)
				)
			)
		)
		(sheetname "Com Express 7 Interfaces")
		(sheetfile "com_express_7_interfaces.kicad_sch")
		(solder_paste_margin_ratio -1)
		(attr smd)
		(fp_circle
			(center 0 0)
			(end 3.05 0)
			(stroke
				(width 0.05)
				(type solid)
			)
			(fill no)
			(layer "F.CrtYd")
		)
		(fp_circle
			(center 0 0)
			(end 2.6 0)
			(stroke
				(width 0.15)
				(type solid)
			)
			(fill no)
			(layer "F.Fab")
		)
		(pad "" smd custom
			(at -1.7 -1.7 90)
			(size 0.62 0.62)
			(layers "F.Paste")
			(thermal_bridge_angle 90)
			(options
				(clearance outline)
				(anchor circle)
			)
			(primitives
				(gr_arc
					(start -0.250195 1.279127)
					(mid 0.285453 0.294389)
					(end 1.266786 -0.24747)
					(width 0.2)
				)
				(gr_arc
					(start -0.34334 1.279127)
					(mid 0.218448 0.232561)
					(end 1.259603 -0.339191)
					(width 0.2)
				)
				(gr_arc
					(start -0.436309 1.279127)
					(mid 0.152481 0.169693)
					(end 1.255279 -0.431435)
					(width 0.2)
				)
				(gr_arc
					(start -0.529126 1.279127)
					(mid 0.087542 0.105784)
					(end 1.253811 -0.524161)
					(width 0.2)
				)
				(gr_arc
					(start -0.621807 1.279127)
					(mid 0.0309 0.033527)
					(end 1.275473 -0.621136)
					(width 0.2)
				)
				(gr_arc
					(start -0.71437 1.279127)
					(mid -0.037758 -0.026651)
					(end 1.263664 -0.711602)
					(width 0.2)
				)
				(gr_arc
					(start -0.806826 1.279127)
					(mid -0.105837 -0.087395)
					(end 1.253435 -0.802342)
					(width 0.2)
				)
				(gr_arc
					(start -0.899187 1.279127)
					(mid -0.165236 -0.156885)
					(end 1.267475 -0.897258)
					(width 0.2)
				)
				(gr_arc
					(start -0.991463 1.279127)
					(mid -0.228522 -0.222449)
					(end 1.270645 -0.990112)
					(width 0.2)
				)
				(gr_arc
					(start -1.083663 1.279127)
					(mid -0.294507 -0.285313)
					(end 1.266278 -1.081674)
					(width 0.2)
				)
				(gr_line
					(start 1.279127 -0.250195)
					(end 1.279127 -1.083663)
					(width 0.2)
				)
				(gr_line
					(start -0.250195 1.279127)
					(end -1.083663 1.279127)
					(width 0.2)
				)
			)
			(teardrops
				(best_length_ratio 0.2)
				(max_length 1)
				(best_width_ratio 0.9)
				(max_width 2)
				(curved_edges yes)
				(filter_ratio 0.9)
				(enabled yes)
				(allow_two_segments yes)
				(prefer_zone_connections yes)
			)
		)
		(pad "" smd custom
			(at -1.7 1.7 180)
			(size 0.62 0.62)
			(layers "F.Paste")
			(thermal_bridge_angle 90)
			(options
				(clearance outline)
				(anchor circle)
			)
			(primitives
				(gr_arc
					(start -0.250195 1.279127)
					(mid 0.285453 0.294389)
					(end 1.266786 -0.24747)
					(width 0.2)
				)
				(gr_arc
					(start -0.34334 1.279127)
					(mid 0.218448 0.232561)
					(end 1.259603 -0.339191)
					(width 0.2)
				)
				(gr_arc
					(start -0.436309 1.279127)
					(mid 0.152481 0.169693)
					(end 1.255279 -0.431435)
					(width 0.2)
				)
				(gr_arc
					(start -0.529126 1.279127)
					(mid 0.087542 0.105784)
					(end 1.253811 -0.524161)
					(width 0.2)
				)
				(gr_arc
					(start -0.621807 1.279127)
					(mid 0.0309 0.033527)
					(end 1.275473 -0.621136)
					(width 0.2)
				)
				(gr_arc
					(start -0.71437 1.279127)
					(mid -0.037758 -0.026651)
					(end 1.263664 -0.711602)
					(width 0.2)
				)
				(gr_arc
					(start -0.806826 1.279127)
					(mid -0.105837 -0.087395)
					(end 1.253435 -0.802342)
					(width 0.2)
				)
				(gr_arc
					(start -0.899187 1.279127)
					(mid -0.165236 -0.156885)
					(end 1.267475 -0.897258)
					(width 0.2)
				)
				(gr_arc
					(start -0.991463 1.279127)
					(mid -0.228522 -0.222449)
					(end 1.270645 -0.990112)
					(width 0.2)
				)
				(gr_arc
					(start -1.083663 1.279127)
					(mid -0.294507 -0.285313)
					(end 1.266278 -1.081674)
					(width 0.2)
				)
				(gr_line
					(start 1.279127 -0.250195)
					(end 1.279127 -1.083663)
					(width 0.2)
				)
				(gr_line
					(start -0.250195 1.279127)
					(end -1.083663 1.279127)
					(width 0.2)
				)
			)
			(teardrops
				(best_length_ratio 0.2)
				(max_length 1)
				(best_width_ratio 0.9)
				(max_width 2)
				(curved_edges yes)
				(filter_ratio 0.9)
				(enabled yes)
				(allow_two_segments yes)
				(prefer_zone_connections yes)
			)
		)
		(pad "" smd custom
			(at 1.7 -1.7)
			(size 0.62 0.62)
			(layers "F.Paste")
			(thermal_bridge_angle 90)
			(options
				(clearance outline)
				(anchor circle)
			)
			(primitives
				(gr_arc
					(start -0.250195 1.279127)
					(mid 0.285453 0.294389)
					(end 1.266786 -0.24747)
					(width 0.2)
				)
				(gr_arc
					(start -0.34334 1.279127)
					(mid 0.218448 0.232561)
					(end 1.259603 -0.339191)
					(width 0.2)
				)
				(gr_arc
					(start -0.436309 1.279127)
					(mid 0.152481 0.169693)
					(end 1.255279 -0.431435)
					(width 0.2)
				)
				(gr_arc
					(start -0.529126 1.279127)
					(mid 0.087542 0.105784)
					(end 1.253811 -0.524161)
					(width 0.2)
				)
				(gr_arc
					(start -0.621807 1.279127)
					(mid 0.0309 0.033527)
					(end 1.275473 -0.621136)
					(width 0.2)
				)
				(gr_arc
					(start -0.71437 1.279127)
					(mid -0.037758 -0.026651)
					(end 1.263664 -0.711602)
					(width 0.2)
				)
				(gr_arc
					(start -0.806826 1.279127)
					(mid -0.105837 -0.087395)
					(end 1.253435 -0.802342)
					(width 0.2)
				)
				(gr_arc
					(start -0.899187 1.279127)
					(mid -0.165236 -0.156885)
					(end 1.267475 -0.897258)
					(width 0.2)
				)
				(gr_arc
					(start -0.991463 1.279127)
					(mid -0.228522 -0.222449)
					(end 1.270645 -0.990112)
					(width 0.2)
				)
				(gr_arc
					(start -1.083663 1.279127)
					(mid -0.294507 -0.285313)
					(end 1.266278 -1.081674)
					(width 0.2)
				)
				(gr_line
					(start 1.279127 -0.250195)
					(end 1.279127 -1.083663)
					(width 0.2)
				)
				(gr_line
					(start -0.250195 1.279127)
					(end -1.083663 1.279127)
					(width 0.2)
				)
			)
			(teardrops
				(best_length_ratio 0.2)
				(max_length 1)
				(best_width_ratio 0.9)
				(max_width 2)
				(curved_edges yes)
				(filter_ratio 0.9)
				(enabled yes)
				(allow_two_segments yes)
				(prefer_zone_connections yes)
			)
		)
		(pad "" smd custom
			(at 1.7 1.7 270)
			(size 0.62 0.62)
			(layers "F.Paste")
			(thermal_bridge_angle 90)
			(options
				(clearance outline)
				(anchor circle)
			)
			(primitives
				(gr_arc
					(start -0.250195 1.279127)
					(mid 0.285453 0.294389)
					(end 1.266786 -0.24747)
					(width 0.2)
				)
				(gr_arc
					(start -0.34334 1.279127)
					(mid 0.218448 0.232561)
					(end 1.259603 -0.339191)
					(width 0.2)
				)
				(gr_arc
					(start -0.436309 1.279127)
					(mid 0.152481 0.169693)
					(end 1.255279 -0.431435)
					(width 0.2)
				)
				(gr_arc
					(start -0.529126 1.279127)
					(mid 0.087542 0.105784)
					(end 1.253811 -0.524161)
					(width 0.2)
				)
				(gr_arc
					(start -0.621807 1.279127)
					(mid 0.0309 0.033527)
					(end 1.275473 -0.621136)
					(width 0.2)
				)
				(gr_arc
					(start -0.71437 1.279127)
					(mid -0.037758 -0.026651)
					(end 1.263664 -0.711602)
					(width 0.2)
				)
				(gr_arc
					(start -0.806826 1.279127)
					(mid -0.105837 -0.087395)
					(end 1.253435 -0.802342)
					(width 0.2)
				)
				(gr_arc
					(start -0.899187 1.279127)
					(mid -0.165236 -0.156885)
					(end 1.267475 -0.897258)
					(width 0.2)
				)
				(gr_arc
					(start -0.991463 1.279127)
					(mid -0.228522 -0.222449)
					(end 1.270645 -0.990112)
					(width 0.2)
				)
				(gr_arc
					(start -1.083663 1.279127)
					(mid -0.294507 -0.285313)
					(end 1.266278 -1.081674)
					(width 0.2)
				)
				(gr_line
					(start 1.279127 -0.250195)
					(end 1.279127 -1.083663)
					(width 0.2)
				)
				(gr_line
					(start -0.250195 1.279127)
					(end -1.083663 1.279127)
					(width 0.2)
				)
			)
			(teardrops
				(best_length_ratio 0.2)
				(max_length 1)
				(best_width_ratio 0.9)
				(max_width 2)
				(curved_edges yes)
				(filter_ratio 0.9)
				(enabled yes)
				(allow_two_segments yes)
				(prefer_zone_connections yes)
			)
		)
		(pad "1" thru_hole circle
			(at 0 0 90)
			(size 6 6)
			(drill 3.7)
			(layers "*.Cu" "*.Mask")
			(remove_unused_layers no)
			(net 1 "GND")
			(pintype "passive")
			(teardrops
				(best_length_ratio 0.4)
				(max_length 1)
				(best_width_ratio 0.9)
				(max_width 2)
				(curved_edges yes)
				(filter_ratio 0.9)
				(enabled yes)
				(allow_two_segments yes)
				(prefer_zone_connections yes)
			)
		)
	)
	(footprint "antmicro-footprints:R_0402_1005Metric"
		(layer "F.Cu")
		(at 191.635786 128.785786 -135)
		(descr "Resistor SMD 0402")
		(tags "resistor SMD 0402")
		(property "Reference" "R220"
			(at -3.65 -0.4 45)
			(layer "F.SilkS")
			(effects
				(font
					(size 0.7 0.7)
					(thickness 0.15)
				)
				(justify right bottom)
			)
		)
		(property "Value" "R_1k_0402"
			(at -1.011843 1.772046 45)
			(layer "F.Fab")
			(effects
				(font
					(size 0.7 0.7)
					(thickness 0.15)
				)
				(justify right bottom)
			)
		)
		(property "Datasheet" "https://www.bourns.com/docs/product-datasheets/cr.pdf"
			(at 0 0 45)
			(layer "F.Fab")
			(hide yes)
			(effects
				(font
					(size 1.27 1.27)
					(thickness 0.15)
				)
			)
		)
		(property "Author" "Antmicro"
			(at 389.1 259.22 45)
			(layer "F.Fab")
			(hide yes)
			(effects
				(font
					(size 1 1)
					(thickness 0.15)
				)
			)
		)
		(property "License" "Apache-2.0"
			(at 389.1 259.22 45)
			(layer "F.Fab")
			(hide yes)
			(effects
				(font
					(size 1 1)
					(thickness 0.15)
				)
			)
		)
		(property "MPN" "CR0402-FX-1001GLF"
			(at 389.1 259.22 45)
			(layer "F.Fab")
			(hide yes)
			(effects
				(font
					(size 1 1)
					(thickness 0.15)
				)
			)
		)
		(property "Manufacturer" "Bourns"
			(at 389.1 259.22 45)
			(layer "F.Fab")
			(hide yes)
			(effects
				(font
					(size 1 1)
					(thickness 0.15)
				)
			)
		)
		(property "Public" "False"
			(at 389.1 259.22 45)
			(layer "F.Fab")
			(hide yes)
			(effects
				(font
					(size 1 1)
					(thickness 0.15)
				)
			)
		)
		(property "Tolerance" "1%"
			(at 389.1 259.22 45)
			(layer "F.Fab")
			(hide yes)
			(effects
				(font
					(size 1 1)
					(thickness 0.15)
				)
			)
		)
		(property "Val" "1k"
			(at 389.1 259.22 45)
			(layer "F.Fab")
			(hide yes)
			(effects
				(font
					(size 1 1)
					(thickness 0.15)
				)
			)
		)
		(sheetname "PCIe redriver")
		(sheetfile "pcie_redriver.kicad_sch")
		(attr smd dnp)
		(fp_poly
			(pts
				(xy -0.925 -0.47) (xy 0.925 -0.47) (xy 0.925 0.47) (xy -0.925 0.47)
			)
			(stroke
				(width 0.05)
				(type default)
			)
			(fill no)
			(layer "F.CrtYd")
		)
		(fp_poly
			(pts
				(xy -0.5 -0.25) (xy 0.5 -0.25) (xy 0.5 0.25) (xy -0.5 0.25)
			)
			(stroke
				(width 0.15)
				(type solid)
			)
			(fill no)
			(layer "F.Fab")
		)
		(pad "1" smd roundrect
			(at -0.48 0 225)
			(size 0.59 0.64)
			(layers "F.Cu" "F.Mask" "F.Paste")
			(roundrect_rratio 0.25)
			(net 1 "GND")
			(pintype "passive")
			(teardrops
				(best_length_ratio 0.2)
				(max_length 1)
				(best_width_ratio 0.9)
				(max_width 2)
				(curved_edges yes)
				(filter_ratio 0.9)
				(enabled yes)
				(allow_two_segments yes)
				(prefer_zone_connections yes)
			)
		)
		(pad "2" smd roundrect
			(at 0.48 0 225)
			(size 0.59 0.64)
			(layers "F.Cu" "F.Mask" "F.Paste")
			(roundrect_rratio 0.25)
			(net 973 "/PCIe redriver/RX_SW")
			(pintype "passive")
			(teardrops
				(best_length_ratio 0.2)
				(max_length 1)
				(best_width_ratio 0.9)
				(max_width 2)
				(curved_edges yes)
				(filter_ratio 0.9)
				(enabled yes)
				(allow_two_segments yes)
				(prefer_zone_connections yes)
			)
		)
	)
)
